(kicad_pcb
	(version 20260206)
	(generator "pcbnew")
	(generator_version "10.0")
	(general
		(thickness 1.6)
		(legacy_teardrops no)
	)
	(paper "A4")
	(title_block
		(title "01162023_DA0F0TEBIF0_F0T_Expander_BD_F_brd_V02_OCP.brd")
		(comment 1 "Grand Teton / footprints 6463-6469 of 9728")
	)
	(layers
		(0 "F.Cu" signal "TOP")
		(4 "In1.Cu" signal "GND")
		(6 "In2.Cu" signal "VCC")
		(8 "In3.Cu" signal "VCC1")
		(10 "In4.Cu" signal "GND1")
		(12 "In5.Cu" signal "IN1")
		(14 "In6.Cu" signal "GND2")
		(16 "In7.Cu" signal "IN2")
		(18 "In8.Cu" signal "GND3")
		(20 "In9.Cu" signal "IN3")
		(22 "In10.Cu" signal "GND4")
		(24 "In11.Cu" signal "IN4")
		(26 "In12.Cu" signal "GND5")
		(28 "In13.Cu" signal "IN5")
		(30 "In14.Cu" signal "GND6")
		(32 "In15.Cu" signal "IN6")
		(34 "In16.Cu" signal "GND7")
		(2 "B.Cu" signal "BOTTOM")
		(9 "F.Adhes" user "F.Adhesive")
		(11 "B.Adhes" user "B.Adhesive")
		(13 "F.Paste" user "Package Geometry/Pastemask Top")
		(15 "B.Paste" user "Package Geometry/Pastemask Bottom")
		(5 "F.SilkS" user "Ref Des/Silkscreen Top")
		(7 "B.SilkS" user "Ref Des/Silkscreen Bottom")
		(1 "F.Mask" user "Board Geometry/Soldermask Top")
		(3 "B.Mask" user "Board Geometry/Soldermask Bottom")
		(17 "Dwgs.User" user "User.Drawings")
		(19 "Cmts.User" user "User.Comments")
		(21 "Eco1.User" user "User.Eco1")
		(23 "Eco2.User" user "User.Eco2")
		(25 "Edge.Cuts" user "Board Geometry/Outline")
		(27 "Margin" user)
		(31 "F.CrtYd" user "Package Geometry/Place Bound Top")
		(29 "B.CrtYd" user "Package Geometry/Place Bound Bottom")
		(35 "F.Fab" user "Ref Des/Assembly Top")
		(33 "B.Fab" user "Ref Des/Assembly Bottom")
	)
	(footprint ""
		(layer "F.Cu")
		(at 175.510952 -350.098614 90)
		(property "Reference" "C2525"
			(at 0 0 90)
			(layer "F.SilkS")
			(hide yes)
			(effects
				(font
					(size 1.27 1.27)
				)
			)
		)
		(property "Value" ""
			(at 0 0 90)
			(layer "F.Fab")
			(effects
				(font
					(size 1.27 1.27)
				)
			)
		)
		(duplicate_pad_numbers_are_jumpers no)
		(fp_line
			(start 0.299974 -0.150114)
			(end 0.299974 0.150114)
			(stroke
				(width 0.1)
				(type default)
			)
			(layer "F.Fab")
		)
		(fp_line
			(start -0.299974 -0.150114)
			(end 0.299974 -0.150114)
			(stroke
				(width 0.1)
				(type default)
			)
			(layer "F.Fab")
		)
		(fp_line
			(start 0.299974 0.150114)
			(end -0.299974 0.150114)
			(stroke
				(width 0.1)
				(type default)
			)
			(layer "F.Fab")
		)
		(fp_line
			(start -0.299974 0.150114)
			(end -0.299974 -0.150114)
			(stroke
				(width 0.1)
				(type default)
			)
			(layer "F.Fab")
		)
		(pad "1" smd rect
			(at -0.2667 0 90)
			(size 0.3048 0.381)
			(layers "F.Cu" "F.Mask" "F.Paste")
			(net "P5E_PEX1_STN4_TX_DN<73>")
		)
		(pad "2" smd rect
			(at 0.2667 0 90)
			(size 0.3048 0.381)
			(layers "F.Cu" "F.Mask" "F.Paste")
			(net "P5E_PEX1_STN4_TX_C_DN<73>")
		)
	)
	(footprint ""
		(layer "F.Cu")
		(at 271.480534 -121.919746)
		(property "Reference" "C468"
			(at 0 0 0)
			(layer "F.SilkS")
			(hide yes)
			(effects
				(font
					(size 1.27 1.27)
				)
			)
		)
		(property "Value" ""
			(at 0 0 0)
			(layer "F.Fab")
			(effects
				(font
					(size 1.27 1.27)
				)
			)
		)
		(duplicate_pad_numbers_are_jumpers no)
		(fp_line
			(start -0.299974 -0.150114)
			(end 0.299974 -0.150114)
			(stroke
				(width 0.1)
				(type default)
			)
			(layer "F.Fab")
		)
		(fp_line
			(start -0.299974 0.150114)
			(end -0.299974 -0.150114)
			(stroke
				(width 0.1)
				(type default)
			)
			(layer "F.Fab")
		)
		(fp_line
			(start 0.299974 -0.150114)
			(end 0.299974 0.150114)
			(stroke
				(width 0.1)
				(type default)
			)
			(layer "F.Fab")
		)
		(fp_line
			(start 0.299974 0.150114)
			(end -0.299974 0.150114)
			(stroke
				(width 0.1)
				(type default)
			)
			(layer "F.Fab")
		)
		(pad "1" smd rect
			(at -0.2667 0)
			(size 0.3048 0.381)
			(layers "F.Cu" "F.Mask" "F.Paste")
			(net "P5E_PEX2_STN1_TX_DP<25>")
		)
		(pad "2" smd rect
			(at 0.2667 0)
			(size 0.3048 0.381)
			(layers "F.Cu" "F.Mask" "F.Paste")
			(net "P5E_PEX2_STN1_TX_C_DP<25>")
		)
	)
	(footprint ""
		(layer "F.Cu")
		(at 375.230136 -290.805108 -90)
		(property "Reference" "C3557"
			(at 0 0 270)
			(layer "F.SilkS")
			(hide yes)
			(effects
				(font
					(size 1.27 1.27)
				)
			)
		)
		(property "Value" ""
			(at 0 0 270)
			(layer "F.Fab")
			(effects
				(font
					(size 1.27 1.27)
				)
			)
		)
		(duplicate_pad_numbers_are_jumpers no)
		(fp_line
			(start -1.2954 0.5842)
			(end -1.2954 -0.5842)
			(stroke
				(width 0.1524)
				(type default)
			)
			(layer "F.SilkS")
		)
		(fp_line
			(start 1.2954 0.5842)
			(end -1.2954 0.5842)
			(stroke
				(width 0.1524)
				(type default)
			)
			(layer "F.SilkS")
		)
		(fp_line
			(start -1.2954 -0.5842)
			(end 1.2954 -0.5842)
			(stroke
				(width 0.1524)
				(type default)
			)
			(layer "F.SilkS")
		)
		(fp_line
			(start 1.2954 -0.5842)
			(end 1.2954 0.5842)
			(stroke
				(width 0.1524)
				(type default)
			)
			(layer "F.SilkS")
		)
		(fp_line
			(start -0.8636 0.4572)
			(end -0.8636 0.4064)
			(stroke
				(width 0.1)
				(type default)
			)
			(layer "F.Fab")
		)
		(fp_line
			(start 0.8636 0.4572)
			(end -0.8636 0.4572)
			(stroke
				(width 0.1)
				(type default)
			)
			(layer "F.Fab")
		)
		(fp_line
			(start -1.1938 0.4064)
			(end -1.1938 -0.4064)
			(stroke
				(width 0.1)
				(type default)
			)
			(layer "F.Fab")
		)
		(fp_line
			(start -0.8636 0.4064)
			(end -1.1938 0.4064)
			(stroke
				(width 0.1)
				(type default)
			)
			(layer "F.Fab")
		)
		(fp_line
			(start 0.8636 0.4064)
			(end 0.8636 0.4572)
			(stroke
				(width 0.1)
				(type default)
			)
			(layer "F.Fab")
		)
		(fp_line
			(start 1.1938 0.4064)
			(end 0.8636 0.4064)
			(stroke
				(width 0.1)
				(type default)
			)
			(layer "F.Fab")
		)
		(fp_line
			(start -1.1938 -0.4064)
			(end -0.8636 -0.4064)
			(stroke
				(width 0.1)
				(type default)
			)
			(layer "F.Fab")
		)
		(fp_line
			(start -0.8636 -0.4064)
			(end -0.8636 -0.4572)
			(stroke
				(width 0.1)
				(type default)
			)
			(layer "F.Fab")
		)
		(fp_line
			(start 0.8636 -0.4064)
			(end 1.1938 -0.4064)
			(stroke
				(width 0.1)
				(type default)
			)
			(layer "F.Fab")
		)
		(fp_line
			(start 1.1938 -0.4064)
			(end 1.1938 0.4064)
			(stroke
				(width 0.1)
				(type default)
			)
			(layer "F.Fab")
		)
		(fp_line
			(start -0.8636 -0.4572)
			(end 0.8636 -0.4572)
			(stroke
				(width 0.1)
				(type default)
			)
			(layer "F.Fab")
		)
		(fp_line
			(start 0.8636 -0.4572)
			(end 0.8636 -0.4064)
			(stroke
				(width 0.1)
				(type default)
			)
			(layer "F.Fab")
		)
		(pad "1" smd rect
			(at -0.7366 0 180)
			(size 0.7112 0.8128)
			(layers "F.Cu" "F.Mask" "F.Paste")
			(net "P1V8_PLL0_PEX3")
		)
		(pad "2" smd rect
			(at 0.7366 0 180)
			(size 0.7112 0.8128)
			(layers "F.Cu" "F.Mask" "F.Paste")
			(net "GND")
		)
	)
	(footprint ""
		(layer "F.Cu")
		(at 214.466678 -213.180168 180)
		(property "Reference" "R5772"
			(at 0 0 180)
			(layer "F.SilkS")
			(hide yes)
			(effects
				(font
					(size 1.27 1.27)
				)
			)
		)
		(property "Value" ""
			(at 0 0 180)
			(layer "F.Fab")
			(effects
				(font
					(size 1.27 1.27)
				)
			)
		)
		(duplicate_pad_numbers_are_jumpers no)
		(fp_line
			(start 0.7874 0.4064)
			(end -0.7874 0.4064)
			(stroke
				(width 0.1524)
				(type default)
			)
			(layer "F.SilkS")
		)
		(fp_line
			(start 0.7874 -0.4064)
			(end 0.7874 0.4064)
			(stroke
				(width 0.1524)
				(type default)
			)
			(layer "F.SilkS")
		)
		(fp_line
			(start -0.7874 0.4064)
			(end -0.7874 -0.4064)
			(stroke
				(width 0.1524)
				(type default)
			)
			(layer "F.SilkS")
		)
		(fp_line
			(start -0.7874 -0.4064)
			(end 0.7874 -0.4064)
			(stroke
				(width 0.1524)
				(type default)
			)
			(layer "F.SilkS")
		)
		(fp_line
			(start 0.67945 0.3048)
			(end 0.120396 0.3048)
			(stroke
				(width 0.1)
				(type default)
			)
			(layer "F.Fab")
		)
		(fp_line
			(start 0.67945 -0.3048)
			(end 0.67945 0.3048)
			(stroke
				(width 0.1)
				(type default)
			)
			(layer "F.Fab")
		)
		(fp_line
			(start 0.12065 -0.2794)
			(end 0.12065 -0.3048)
			(stroke
				(width 0.1)
				(type default)
			)
			(layer "F.Fab")
		)
		(fp_line
			(start 0.12065 -0.3048)
			(end 0.67945 -0.3048)
			(stroke
				(width 0.1)
				(type default)
			)
			(layer "F.Fab")
		)
		(fp_line
			(start 0.120396 0.3048)
			(end 0.120396 0.2794)
			(stroke
				(width 0.1)
				(type default)
			)
			(layer "F.Fab")
		)
		(fp_line
			(start 0.120396 0.2794)
			(end -0.12065 0.2794)
			(stroke
				(width 0.1)
				(type default)
			)
			(layer "F.Fab")
		)
		(fp_line
			(start -0.12065 0.3048)
			(end -0.67945 0.3048)
			(stroke
				(width 0.1)
				(type default)
			)
			(layer "F.Fab")
		)
		(fp_line
			(start -0.12065 0.2794)
			(end -0.12065 0.3048)
			(stroke
				(width 0.1)
				(type default)
			)
			(layer "F.Fab")
		)
		(fp_line
			(start -0.12065 -0.2794)
			(end 0.12065 -0.2794)
			(stroke
				(width 0.1)
				(type default)
			)
			(layer "F.Fab")
		)
		(fp_line
			(start -0.12065 -0.305054)
			(end -0.12065 -0.2794)
			(stroke
				(width 0.1)
				(type default)
			)
			(layer "F.Fab")
		)
		(fp_line
			(start -0.67945 0.3048)
			(end -0.67945 -0.305054)
			(stroke
				(width 0.1)
				(type default)
			)
			(layer "F.Fab")
		)
		(fp_line
			(start -0.67945 -0.305054)
			(end -0.12065 -0.305054)
			(stroke
				(width 0.1)
				(type default)
			)
			(layer "F.Fab")
		)
		(pad "1" smd circle
			(at -0.40005 0 180)
			(size 0 0)
			(layers "F.Cu" "F.Mask" "F.Paste")
			(net "SMB_ALERT_PMBUS_R_N")
		)
		(pad "2" smd circle
			(at 0.40005 0 180)
			(size 0 0)
			(layers "F.Cu" "F.Mask" "F.Paste")
			(net "P0V8_PEX0_SMBALERT")
		)
	)
	(footprint ""
		(layer "F.Cu")
		(at 230.749094 -176.72558 180)
		(property "Reference" "C3647"
			(at 0 0 180)
			(layer "F.SilkS")
			(hide yes)
			(effects
				(font
					(size 1.27 1.27)
				)
			)
		)
		(property "Value" ""
			(at 0 0 180)
			(layer "F.Fab")
			(effects
				(font
					(size 1.27 1.27)
				)
			)
		)
		(duplicate_pad_numbers_are_jumpers no)
		(fp_line
			(start 0.7874 0.4064)
			(end -0.7874 0.4064)
			(stroke
				(width 0.1524)
				(type default)
			)
			(layer "F.SilkS")
		)
		(fp_line
			(start 0.7874 -0.4064)
			(end 0.7874 0.4064)
			(stroke
				(width 0.1524)
				(type default)
			)
			(layer "F.SilkS")
		)
		(fp_line
			(start -0.7874 0.4064)
			(end -0.7874 -0.4064)
			(stroke
				(width 0.1524)
				(type default)
			)
			(layer "F.SilkS")
		)
		(fp_line
			(start -0.7874 -0.4064)
			(end 0.7874 -0.4064)
			(stroke
				(width 0.1524)
				(type default)
			)
			(layer "F.SilkS")
		)
		(fp_line
			(start 0.67945 0.3048)
			(end 0.120396 0.3048)
			(stroke
				(width 0.1)
				(type default)
			)
			(layer "F.Fab")
		)
		(fp_line
			(start 0.67945 -0.3048)
			(end 0.67945 0.3048)
			(stroke
				(width 0.1)
				(type default)
			)
			(layer "F.Fab")
		)
		(fp_line
			(start 0.12065 -0.2794)
			(end 0.12065 -0.3048)
			(stroke
				(width 0.1)
				(type default)
			)
			(layer "F.Fab")
		)
		(fp_line
			(start 0.12065 -0.3048)
			(end 0.67945 -0.3048)
			(stroke
				(width 0.1)
				(type default)
			)
			(layer "F.Fab")
		)
		(fp_line
			(start 0.120396 0.3048)
			(end 0.120396 0.2794)
			(stroke
				(width 0.1)
				(type default)
			)
			(layer "F.Fab")
		)
		(fp_line
			(start 0.120396 0.2794)
			(end -0.12065 0.2794)
			(stroke
				(width 0.1)
				(type default)
			)
			(layer "F.Fab")
		)
		(fp_line
			(start -0.12065 0.3048)
			(end -0.67945 0.3048)
			(stroke
				(width 0.1)
				(type default)
			)
			(layer "F.Fab")
		)
		(fp_line
			(start -0.12065 0.2794)
			(end -0.12065 0.3048)
			(stroke
				(width 0.1)
				(type default)
			)
			(layer "F.Fab")
		)
		(fp_line
			(start -0.12065 -0.2794)
			(end 0.12065 -0.2794)
			(stroke
				(width 0.1)
				(type default)
			)
			(layer "F.Fab")
		)
		(fp_line
			(start -0.12065 -0.305054)
			(end -0.12065 -0.2794)
			(stroke
				(width 0.1)
				(type default)
			)
			(layer "F.Fab")
		)
		(fp_line
			(start -0.67945 0.3048)
			(end -0.67945 -0.305054)
			(stroke
				(width 0.1)
				(type default)
			)
			(layer "F.Fab")
		)
		(fp_line
			(start -0.67945 -0.305054)
			(end -0.12065 -0.305054)
			(stroke
				(width 0.1)
				(type default)
			)
			(layer "F.Fab")
		)
		(pad "1" smd circle
			(at -0.40005 0 180)
			(size 0 0)
			(layers "F.Cu" "F.Mask" "F.Paste")
			(net "GND")
		)
		(pad "2" smd circle
			(at 0.40005 0 180)
			(size 0 0)
			(layers "F.Cu" "F.Mask" "F.Paste")
			(net "THRESHOLD")
		)
	)
	(footprint ""
		(layer "F.Cu")
		(at 331.147166 -20.35556)
		(property "Reference" "C3955"
			(at 0 0 0)
			(layer "F.SilkS")
			(hide yes)
			(effects
				(font
					(size 1.27 1.27)
				)
			)
		)
		(property "Value" ""
			(at 0 0 0)
			(layer "F.Fab")
			(effects
				(font
					(size 1.27 1.27)
				)
			)
		)
		(duplicate_pad_numbers_are_jumpers no)
		(fp_line
			(start -0.7874 -0.4064)
			(end 0.7874 -0.4064)
			(stroke
				(width 0.1524)
				(type default)
			)
			(layer "F.SilkS")
		)
		(fp_line
			(start -0.7874 0.4064)
			(end -0.7874 -0.4064)
			(stroke
				(width 0.1524)
				(type default)
			)
			(layer "F.SilkS")
		)
		(fp_line
			(start 0.7874 -0.4064)
			(end 0.7874 0.4064)
			(stroke
				(width 0.1524)
				(type default)
			)
			(layer "F.SilkS")
		)
		(fp_line
			(start 0.7874 0.4064)
			(end -0.7874 0.4064)
			(stroke
				(width 0.1524)
				(type default)
			)
			(layer "F.SilkS")
		)
		(fp_line
			(start -0.67945 -0.305054)
			(end -0.12065 -0.305054)
			(stroke
				(width 0.1)
				(type default)
			)
			(layer "F.Fab")
		)
		(fp_line
			(start -0.67945 0.3048)
			(end -0.67945 -0.305054)
			(stroke
				(width 0.1)
				(type default)
			)
			(layer "F.Fab")
		)
		(fp_line
			(start -0.12065 -0.305054)
			(end -0.12065 -0.2794)
			(stroke
				(width 0.1)
				(type default)
			)
			(layer "F.Fab")
		)
		(fp_line
			(start -0.12065 -0.2794)
			(end 0.12065 -0.2794)
			(stroke
				(width 0.1)
				(type default)
			)
			(layer "F.Fab")
		)
		(fp_line
			(start -0.12065 0.2794)
			(end -0.12065 0.3048)
			(stroke
				(width 0.1)
				(type default)
			)
			(layer "F.Fab")
		)
		(fp_line
			(start -0.12065 0.3048)
			(end -0.67945 0.3048)
			(stroke
				(width 0.1)
				(type default)
			)
			(layer "F.Fab")
		)
		(fp_line
			(start 0.120396 0.2794)
			(end -0.12065 0.2794)
			(stroke
				(width 0.1)
				(type default)
			)
			(layer "F.Fab")
		)
		(fp_line
			(start 0.120396 0.3048)
			(end 0.120396 0.2794)
			(stroke
				(width 0.1)
				(type default)
			)
			(layer "F.Fab")
		)
		(fp_line
			(start 0.12065 -0.3048)
			(end 0.67945 -0.3048)
			(stroke
				(width 0.1)
				(type default)
			)
			(layer "F.Fab")
		)
		(fp_line
			(start 0.12065 -0.2794)
			(end 0.12065 -0.3048)
			(stroke
				(width 0.1)
				(type default)
			)
			(layer "F.Fab")
		)
		(fp_line
			(start 0.67945 -0.3048)
			(end 0.67945 0.3048)
			(stroke
				(width 0.1)
				(type default)
			)
			(layer "F.Fab")
		)
		(fp_line
			(start 0.67945 0.3048)
			(end 0.120396 0.3048)
			(stroke
				(width 0.1)
				(type default)
			)
			(layer "F.Fab")
		)
		(pad "1" smd circle
			(at -0.40005 0)
			(size 0 0)
			(layers "F.Cu" "F.Mask" "F.Paste")
			(net "P12V_SSD11")
		)
		(pad "2" smd circle
			(at 0.40005 0)
			(size 0 0)
			(layers "F.Cu" "F.Mask" "F.Paste")
			(net "GND")
		)
	)
	(footprint ""
		(layer "F.Cu")
		(at 451.638416 -374.471692 90)
		(property "Reference" "R6685"
			(at 0 0 90)
			(layer "F.SilkS")
			(hide yes)
			(effects
				(font
					(size 1.27 1.27)
				)
			)
		)
		(property "Value" ""
			(at 0 0 90)
			(layer "F.Fab")
			(effects
				(font
					(size 1.27 1.27)
				)
			)
		)
		(duplicate_pad_numbers_are_jumpers no)
		(fp_line
			(start 0.7874 -0.4064)
			(end 0.7874 0.4064)
			(stroke
				(width 0.1524)
				(type default)
			)
			(layer "F.SilkS")
		)
		(fp_line
			(start -0.7874 -0.4064)
			(end 0.7874 -0.4064)
			(stroke
				(width 0.1524)
				(type default)
			)
			(layer "F.SilkS")
		)
		(fp_line
			(start 0.7874 0.4064)
			(end -0.7874 0.4064)
			(stroke
				(width 0.1524)
				(type default)
			)
			(layer "F.SilkS")
		)
		(fp_line
			(start -0.7874 0.4064)
			(end -0.7874 -0.4064)
			(stroke
				(width 0.1524)
				(type default)
			)
			(layer "F.SilkS")
		)
		(fp_line
			(start -0.12065 -0.305054)
			(end -0.12065 -0.2794)
			(stroke
				(width 0.1)
				(type default)
			)
			(layer "F.Fab")
		)
		(fp_line
			(start -0.67945 -0.305054)
			(end -0.12065 -0.305054)
			(stroke
				(width 0.1)
				(type default)
			)
			(layer "F.Fab")
		)
		(fp_line
			(start 0.67945 -0.3048)
			(end 0.67945 0.3048)
			(stroke
				(width 0.1)
				(type default)
			)
			(layer "F.Fab")
		)
		(fp_line
			(start 0.12065 -0.3048)
			(end 0.67945 -0.3048)
			(stroke
				(width 0.1)
				(type default)
			)
			(layer "F.Fab")
		)
		(fp_line
			(start 0.12065 -0.2794)
			(end 0.12065 -0.3048)
			(stroke
				(width 0.1)
				(type default)
			)
			(layer "F.Fab")
		)
		(fp_line
			(start -0.12065 -0.2794)
			(end 0.12065 -0.2794)
			(stroke
				(width 0.1)
				(type default)
			)
			(layer "F.Fab")
		)
		(fp_line
			(start 0.120396 0.2794)
			(end -0.12065 0.2794)
			(stroke
				(width 0.1)
				(type default)
			)
			(layer "F.Fab")
		)
		(fp_line
			(start -0.12065 0.2794)
			(end -0.12065 0.3048)
			(stroke
				(width 0.1)
				(type default)
			)
			(layer "F.Fab")
		)
		(fp_line
			(start 0.67945 0.3048)
			(end 0.120396 0.3048)
			(stroke
				(width 0.1)
				(type default)
			)
			(layer "F.Fab")
		)
		(fp_line
			(start 0.120396 0.3048)
			(end 0.120396 0.2794)
			(stroke
				(width 0.1)
				(type default)
			)
			(layer "F.Fab")
		)
		(fp_line
			(start -0.12065 0.3048)
			(end -0.67945 0.3048)
			(stroke
				(width 0.1)
				(type default)
			)
			(layer "F.Fab")
		)
		(fp_line
			(start -0.67945 0.3048)
			(end -0.67945 -0.305054)
			(stroke
				(width 0.1)
				(type default)
			)
			(layer "F.Fab")
		)
		(pad "1" smd circle
			(at -0.40005 0 90)
			(size 0 0)
			(layers "F.Cu" "F.Mask" "F.Paste")
			(net "P3V3_AUX")
		)
		(pad "2" smd circle
			(at 0.40005 0 90)
			(size 0 0)
			(layers "F.Cu" "F.Mask" "F.Paste")
			(net "GPU_3V3IO_RSVD3")
		)
	)
)
